(kicad_pcb
	(version 20260206)
	(generator "pcbnew")
	(generator_version "10.0")
	(general
		(thickness 1.6)
		(legacy_teardrops no)
	)
	(paper "A4")
	(title_block
		(title "v2-pdb — ms_pdb_v2.brd")
		(comment 1 "Open CloudServer (Microsoft) / footprint 117 of 348 (J25), pads 157-166 of 166")
	)
	(layers
		(0 "F.Cu" signal "TOP")
		(4 "In1.Cu" signal "GND")
		(6 "In2.Cu" signal "IN1")
		(8 "In3.Cu" signal "VCC")
		(10 "In4.Cu" signal "VCC1")
		(12 "In5.Cu" signal "IN2")
		(14 "In6.Cu" signal "GND1")
		(2 "B.Cu" signal "BOTTOM")
		(9 "F.Adhes" user "F.Adhesive")
		(11 "B.Adhes" user "B.Adhesive")
		(13 "F.Paste" user "Package Geometry/Pastemask Top")
		(15 "B.Paste" user "Package Geometry/Pastemask Bottom")
		(5 "F.SilkS" user "Ref Des/Silkscreen Top")
		(7 "B.SilkS" user "Ref Des/Silkscreen Bottom")
		(1 "F.Mask" user "Board Geometry/Soldermask Top")
		(3 "B.Mask" user "Board Geometry/Soldermask Bottom")
		(17 "Dwgs.User" user "User.Drawings")
		(19 "Cmts.User" user "User.Comments")
		(21 "Eco1.User" user "User.Eco1")
		(23 "Eco2.User" user "User.Eco2")
		(25 "Edge.Cuts" user "Board Geometry/Outline")
		(27 "Margin" user)
		(31 "F.CrtYd" user "Package Geometry/Place Bound Top")
		(29 "B.CrtYd" user "Package Geometry/Place Bound Bottom")
		(35 "F.Fab" user "Ref Des/Assembly Top")
		(33 "B.Fab" user "Ref Des/Assembly Bottom")
	)
	(footprint ""
		(layer "F.Cu")
		(at 6.449822 -352.669856)
		(property "Reference" "J25"
			(at 6.653784 1.81356 90)
			(unlocked yes)
			(layer "F.SilkS")
			(effects
				(font
					(size 0.7874 0.5842)
					(thickness 0.1524)
				)
				(justify left)
			)
		)
		(property "Value" ""
			(at 0 0 0)
			(layer "F.Fab")
			(effects
				(font
					(size 1.27 1.27)
				)
			)
		)
		(duplicate_pad_numbers_are_jumpers no)
		(pad "B73" thru_hole circle
			(at -2.499868 74.000106 270)
			(size 1.016 1.016)
			(drill 0.7112)
			(layers "*.Cu" "*.Mask")
			(remove_unused_layers no)
			(net "T8_BLAD4_RXD")
			(clearance 0.1016)
			(thermal_gap 0.1016)
		)
		(pad "B74" thru_hole circle
			(at -4.499864 75.000104 270)
			(size 1.016 1.016)
			(drill 0.7112)
			(layers "*.Cu" "*.Mask")
			(remove_unused_layers no)
			(net "T8_BLAD4_TXD")
			(clearance 0.1016)
			(thermal_gap 0.1016)
		)
		(pad "B75" thru_hole circle
			(at -2.499868 76.000102 270)
			(size 1.016 1.016)
			(drill 0.7112)
			(layers "*.Cu" "*.Mask")
			(remove_unused_layers no)
			(net "GND")
			(clearance 0.1016)
			(thermal_gap 0.1016)
		)
		(pad "B76" thru_hole circle
			(at -4.499864 77.0001 270)
			(size 1.016 1.016)
			(drill 0.7112)
			(layers "*.Cu" "*.Mask")
			(remove_unused_layers no)
			(net "T6_BLAD1_EN")
			(clearance 0.1016)
			(thermal_gap 0.1016)
		)
		(pad "B77" thru_hole circle
			(at -2.499868 78.000098 270)
			(size 1.016 1.016)
			(drill 0.7112)
			(layers "*.Cu" "*.Mask")
			(remove_unused_layers no)
			(net "TP_T6_BLAD2_EN")
			(clearance 0.1016)
			(thermal_gap 0.1016)
		)
		(pad "B78" thru_hole circle
			(at -4.499864 79.000096 270)
			(size 1.016 1.016)
			(drill 0.7112)
			(layers "*.Cu" "*.Mask")
			(remove_unused_layers no)
			(net "T6_BLAD3_EN")
			(clearance 0.1016)
			(thermal_gap 0.1016)
		)
		(pad "B79" thru_hole circle
			(at -2.499868 80.000094 270)
			(size 1.016 1.016)
			(drill 0.7112)
			(layers "*.Cu" "*.Mask")
			(remove_unused_layers no)
			(net "TP_T6_BLAD4_EN")
			(clearance 0.1016)
			(thermal_gap 0.1016)
		)
		(pad "B80" thru_hole circle
			(at -4.499864 81.000092 270)
			(size 1.016 1.016)
			(drill 0.7112)
			(layers "*.Cu" "*.Mask")
			(remove_unused_layers no)
			(net "GND")
			(clearance 0.1016)
			(thermal_gap 0.1016)
		)
		(pad "B81" thru_hole circle
			(at -2.499868 82.00009 270)
			(size 1.016 1.016)
			(drill 0.7112)
			(layers "*.Cu" "*.Mask")
			(remove_unused_layers no)
			(net "T6_BLAD1_RXD")
			(clearance 0.1016)
			(thermal_gap 0.1016)
		)
		(pad "B82" thru_hole circle
			(at -4.499864 83.000088 270)
			(size 1.016 1.016)
			(drill 0.7112)
			(layers "*.Cu" "*.Mask")
			(remove_unused_layers no)
			(net "T6_BLAD1_TXD")
			(clearance 0.1016)
			(thermal_gap 0.1016)
		)
	)
)
